(kicad_pcb
	(version 20260206)
	(generator "pcbnew")
	(generator_version "10.0")
	(general
		(thickness 1.6)
		(legacy_teardrops no)
	)
	(paper "A4")
	(title_block
		(title "peb — Lightning_PEB_BRD.brd")
		(comment 1 "Lightning (Wiwynn / Facebook NVMe JBOF) / footprints 1327-1332 of 2563")
	)
	(layers
		(0 "F.Cu" signal "TOP")
		(4 "In1.Cu" signal "L2GND")
		(6 "In2.Cu" signal "L3")
		(8 "In3.Cu" signal "L4VCC")
		(10 "In4.Cu" signal "L5VCC")
		(12 "In5.Cu" signal "L6")
		(14 "In6.Cu" signal "L7GND")
		(2 "B.Cu" signal "BOTTOM")
		(9 "F.Adhes" user "F.Adhesive")
		(11 "B.Adhes" user "B.Adhesive")
		(13 "F.Paste" user "Package Geometry/Pastemask Top")
		(15 "B.Paste" user "Package Geometry/Pastemask Bottom")
		(5 "F.SilkS" user "Ref Des/Silkscreen Top")
		(7 "B.SilkS" user "Ref Des/Silkscreen Bottom")
		(1 "F.Mask" user "Board Geometry/Soldermask Top")
		(3 "B.Mask" user "Board Geometry/Soldermask Bottom")
		(17 "Dwgs.User" user "User.Drawings")
		(19 "Cmts.User" user "User.Comments")
		(21 "Eco1.User" user "User.Eco1")
		(23 "Eco2.User" user "User.Eco2")
		(25 "Edge.Cuts" user "Board Geometry/Outline")
		(27 "Margin" user)
		(31 "F.CrtYd" user "Package Geometry/Place Bound Top")
		(29 "B.CrtYd" user "Package Geometry/Place Bound Bottom")
		(35 "F.Fab" user "Ref Des/Assembly Top")
		(33 "B.Fab" user "Ref Des/Assembly Bottom")
	)
	(footprint ""
		(layer "F.Cu")
		(at 26.035 -207.518 180)
		(property "Reference" "R9020"
			(at 0 0 180)
			(layer "F.SilkS")
			(hide yes)
			(effects
				(font
					(size 1.27 1.27)
				)
			)
		)
		(property "Value" "D002RL3115F-L-GP"
			(at 3.2258 1.2954 180)
			(unlocked yes)
			(layer "F.Fab")
			(hide yes)
			(effects
				(font
					(size 1.016 1.016)
					(thickness 0.1524)
				)
			)
		)
		(property "Device Type" "RL3115-4PH45"
			(at 3.2258 -0.2286 180)
			(unlocked yes)
			(layer "F.Fab")
			(hide yes)
			(effects
				(font
					(size 1.016 1.016)
					(thickness 0.1524)
				)
			)
		)
		(duplicate_pad_numbers_are_jumpers no)
		(fp_line
			(start 1.9685 1.651)
			(end -1.9685 1.651)
			(stroke
				(width 0.1524)
				(type default)
			)
			(layer "F.SilkS")
		)
		(fp_line
			(start 1.9685 -1.651)
			(end 1.9685 1.651)
			(stroke
				(width 0.1524)
				(type default)
			)
			(layer "F.SilkS")
		)
		(fp_line
			(start -0.5334 -1.7653)
			(end -2.0574 -1.7653)
			(stroke
				(width 0.3302)
				(type default)
			)
			(layer "F.SilkS")
		)
		(fp_line
			(start -1.9685 1.651)
			(end -1.9685 -1.651)
			(stroke
				(width 0.1524)
				(type default)
			)
			(layer "F.SilkS")
		)
		(fp_line
			(start -1.9685 -1.651)
			(end 1.9685 -1.651)
			(stroke
				(width 0.1524)
				(type default)
			)
			(layer "F.SilkS")
		)
		(fp_line
			(start -2.0574 -1.7653)
			(end -2.0574 -0.4064)
			(stroke
				(width 0.3302)
				(type default)
			)
			(layer "F.SilkS")
		)
		(fp_poly
			(pts
				(xy -0.561594 -1.726946) (xy -0.053594 -2.234946) (xy -1.069594 -2.234946)
			)
			(stroke
				(width 0)
				(type default)
			)
			(fill yes)
			(layer "F.SilkS")
		)
		(fp_rect
			(start -1.524 0.7493)
			(end 1.524 -0.7493)
			(stroke
				(width 0)
				(type default)
			)
			(fill no)
			(layer "F.CrtYd")
		)
		(fp_poly
			(pts
				(xy -2.2225 1.905) (xy -2.2225 -1.905) (xy 2.2225 -1.905) (xy 2.2225 -0.7493) (xy -1.524 -0.7493)
				(xy -1.524 0.7493) (xy 1.524 0.7493) (xy 1.524 -0.7366) (xy 2.2225 -0.7366) (xy 2.2225 1.905)
			)
			(stroke
				(width 0)
				(type default)
			)
			(fill no)
			(layer "F.CrtYd")
		)
		(fp_rect
			(start -2.2225 1.905)
			(end 2.2225 -1.905)
			(stroke
				(width 0)
				(type default)
			)
			(fill no)
			(layer "F.Fab")
		)
		(pad "1" smd rect
			(at -0.5715 -0.813562 180)
			(size 2.286 1.143)
			(layers "F.Cu" "F.Mask" "F.Paste")
			(net "MB0_P12V_MAIN_R")
		)
		(pad "2" smd rect
			(at -0.5715 0.813562 180)
			(size 2.286 1.143)
			(layers "F.Cu" "F.Mask" "F.Paste")
			(net "P12V_PCIE")
		)
		(pad "3" smd rect
			(at 1.334008 -0.813562 180)
			(size 0.762 1.143)
			(layers "F.Cu" "F.Mask" "F.Paste")
			(net "MB0_CM_SENSE_R1_N")
		)
		(pad "4" smd rect
			(at 1.334008 0.813562 180)
			(size 0.762 1.143)
			(layers "F.Cu" "F.Mask" "F.Paste")
			(net "MB0_CM_SENSE_R1_P")
		)
		(zone
			(layer "F.Cu")
			(hatch none 0.5)
			(connect_pads
				(clearance 0)
			)
			(min_thickness 0.25)
			(keepout
				(tracks not_allowed)
				(vias allowed)
				(pads allowed)
				(copperpour not_allowed)
				(footprints allowed)
			)
			(placement
				(enabled no)
				(sheetname "")
			)
			(fill
				(thermal_gap 0.5)
				(thermal_bridge_width 0.5)
				(island_removal_mode 0)
			)
			(polygon
				(pts
					(xy 25.4635 -208.2673) (xy 25.081992 -208.2673) (xy 25.081992 -207.760062) (xy 25.4635 -207.760062)
				)
			)
		)
		(zone
			(layer "F.Cu")
			(hatch none 0.5)
			(connect_pads
				(clearance 0)
			)
			(min_thickness 0.25)
			(keepout
				(tracks allowed)
				(vias not_allowed)
				(pads allowed)
				(copperpour not_allowed)
				(footprints allowed)
			)
			(placement
				(enabled no)
				(sheetname "")
			)
			(fill
				(thermal_gap 0.5)
				(thermal_bridge_width 0.5)
				(island_removal_mode 0)
			)
			(polygon
				(pts
					(xy 25.4635 -208.2673) (xy 25.081992 -208.2673) (xy 25.081992 -207.760062) (xy 25.4635 -207.760062)
				)
			)
		)
		(zone
			(layer "F.Cu")
			(hatch none 0.5)
			(connect_pads
				(clearance 0)
			)
			(min_thickness 0.25)
			(keepout
				(tracks not_allowed)
				(vias allowed)
				(pads allowed)
				(copperpour not_allowed)
				(footprints allowed)
			)
			(placement
				(enabled no)
				(sheetname "")
			)
			(fill
				(thermal_gap 0.5)
				(thermal_bridge_width 0.5)
				(island_removal_mode 0)
			)
			(polygon
				(pts
					(xy 25.4635 -207.275938) (xy 25.081992 -207.275938) (xy 25.081992 -206.7687) (xy 25.4635 -206.7687)
				)
			)
		)
		(zone
			(layer "F.Cu")
			(hatch none 0.5)
			(connect_pads
				(clearance 0)
			)
			(min_thickness 0.25)
			(keepout
				(tracks allowed)
				(vias not_allowed)
				(pads allowed)
				(copperpour not_allowed)
				(footprints allowed)
			)
			(placement
				(enabled no)
				(sheetname "")
			)
			(fill
				(thermal_gap 0.5)
				(thermal_bridge_width 0.5)
				(island_removal_mode 0)
			)
			(polygon
				(pts
					(xy 25.4635 -207.275938) (xy 25.081992 -207.275938) (xy 25.081992 -206.7687) (xy 25.4635 -206.7687)
				)
			)
		)
	)
	(footprint ""
		(layer "F.Cu")
		(at 70.485 -34.417)
		(property "Reference" "PR24"
			(at 0 0 0)
			(layer "F.SilkS")
			(hide yes)
			(effects
				(font
					(size 1.27 1.27)
				)
			)
		)
		(property "Value" "2K7R2J-GP"
			(at 0.064008 -3.993896 0)
			(unlocked yes)
			(layer "F.Fab")
			(hide yes)
			(effects
				(font
					(size 1.016 1.016)
					(thickness 0.1524)
				)
			)
		)
		(property "Device Type" "R402H16"
			(at 0.064008 -5.517896 0)
			(unlocked yes)
			(layer "F.Fab")
			(hide yes)
			(effects
				(font
					(size 1.016 1.016)
					(thickness 0.1524)
				)
			)
		)
		(duplicate_pad_numbers_are_jumpers no)
		(fp_line
			(start -0.508 -0.9398)
			(end -0.508 0.9398)
			(stroke
				(width 0.1524)
				(type default)
			)
			(layer "F.SilkS")
		)
		(fp_line
			(start 0.508 -0.9398)
			(end -0.508 -0.9398)
			(stroke
				(width 0.1524)
				(type default)
			)
			(layer "F.SilkS")
		)
		(fp_rect
			(start -0.508 0.9398)
			(end 0.508 -0.9398)
			(stroke
				(width 0)
				(type default)
			)
			(fill no)
			(layer "F.CrtYd")
		)
		(fp_rect
			(start -0.508 0.9398)
			(end 0.508 -0.9398)
			(stroke
				(width 0)
				(type default)
			)
			(fill no)
			(layer "F.Fab")
		)
		(pad "1" smd custom
			(at 0 -0.4445)
			(size 0.1397 0.1397)
			(layers "F.Cu" "F.Mask" "F.Paste")
			(net "P3V3_STBY_EN")
			(options
				(clearance outline)
				(anchor circle)
			)
			(primitives
				(gr_poly
					(pts
						(arc
							(start -0.1778 -0.2794)
							(mid -0.249642 -0.249642)
							(end -0.2794 -0.1778)
						)
						(arc
							(start -0.2794 0.1778)
							(mid -0.249642 0.249642)
							(end -0.1778 0.2794)
						)
						(arc
							(start 0.1778 0.2794)
							(mid 0.249642 0.249642)
							(end 0.2794 0.1778)
						)
						(arc
							(start 0.2794 -0.1778)
							(mid 0.249642 -0.249642)
							(end 0.1778 -0.2794)
						)
					)
					(width 0)
					(fill yes)
				)
			)
		)
		(pad "2" smd custom
			(at 0 0.4445)
			(size 0.1397 0.1397)
			(layers "F.Cu" "F.Mask" "F.Paste")
			(net "AGND_P3V3_STBY")
			(options
				(clearance outline)
				(anchor circle)
			)
			(primitives
				(gr_poly
					(pts
						(arc
							(start -0.1778 -0.2794)
							(mid -0.249642 -0.249642)
							(end -0.2794 -0.1778)
						)
						(arc
							(start -0.2794 0.1778)
							(mid -0.249642 0.249642)
							(end -0.1778 0.2794)
						)
						(arc
							(start 0.1778 0.2794)
							(mid 0.249642 0.249642)
							(end 0.2794 0.1778)
						)
						(arc
							(start 0.2794 -0.1778)
							(mid 0.249642 -0.249642)
							(end 0.1778 -0.2794)
						)
					)
					(width 0)
					(fill yes)
				)
			)
		)
	)
	(footprint ""
		(layer "F.Cu")
		(at 57.3151 -124.7648 90)
		(property "Reference" "R708"
			(at 0 0 90)
			(layer "F.SilkS")
			(hide yes)
			(effects
				(font
					(size 1.27 1.27)
				)
			)
		)
		(property "Value" "0R2J-2-GP"
			(at 0.064008 -3.993896 90)
			(unlocked yes)
			(layer "F.Fab")
			(hide yes)
			(effects
				(font
					(size 1.016 1.016)
					(thickness 0.1524)
				)
			)
		)
		(property "Device Type" "R402H16"
			(at 0.064008 -5.517896 90)
			(unlocked yes)
			(layer "F.Fab")
			(hide yes)
			(effects
				(font
					(size 1.016 1.016)
					(thickness 0.1524)
				)
			)
		)
		(duplicate_pad_numbers_are_jumpers no)
		(fp_line
			(start 0.508 -0.9398)
			(end -0.508 -0.9398)
			(stroke
				(width 0.1524)
				(type default)
			)
			(layer "F.SilkS")
		)
		(fp_line
			(start -0.508 -0.9398)
			(end -0.508 0.9398)
			(stroke
				(width 0.1524)
				(type default)
			)
			(layer "F.SilkS")
		)
		(fp_rect
			(start -0.508 0.9398)
			(end 0.508 -0.9398)
			(stroke
				(width 0)
				(type default)
			)
			(fill no)
			(layer "F.CrtYd")
		)
		(fp_rect
			(start -0.508 0.9398)
			(end 0.508 -0.9398)
			(stroke
				(width 0)
				(type default)
			)
			(fill no)
			(layer "F.Fab")
		)
		(pad "1" smd custom
			(at 0 -0.4445 90)
			(size 0.1397 0.1397)
			(layers "F.Cu" "F.Mask" "F.Paste")
			(net "TCA9554_INT_N_R")
			(options
				(clearance outline)
				(anchor circle)
			)
			(primitives
				(gr_poly
					(pts
						(arc
							(start -0.1778 -0.2794)
							(mid -0.249642 -0.249642)
							(end -0.2794 -0.1778)
						)
						(arc
							(start -0.2794 0.1778)
							(mid -0.249642 0.249642)
							(end -0.1778 0.2794)
						)
						(arc
							(start 0.1778 0.2794)
							(mid 0.249642 0.249642)
							(end 0.2794 0.1778)
						)
						(arc
							(start 0.2794 -0.1778)
							(mid 0.249642 -0.249642)
							(end 0.1778 -0.2794)
						)
					)
					(width 0)
					(fill yes)
				)
			)
		)
		(pad "2" smd custom
			(at 0 0.4445 90)
			(size 0.1397 0.1397)
			(layers "F.Cu" "F.Mask" "F.Paste")
			(net "TCA9554_INT_N")
			(options
				(clearance outline)
				(anchor circle)
			)
			(primitives
				(gr_poly
					(pts
						(arc
							(start -0.1778 -0.2794)
							(mid -0.249642 -0.249642)
							(end -0.2794 -0.1778)
						)
						(arc
							(start -0.2794 0.1778)
							(mid -0.249642 0.249642)
							(end -0.1778 0.2794)
						)
						(arc
							(start 0.1778 0.2794)
							(mid 0.249642 0.249642)
							(end 0.2794 0.1778)
						)
						(arc
							(start 0.2794 -0.1778)
							(mid 0.249642 -0.249642)
							(end 0.1778 -0.2794)
						)
					)
					(width 0)
					(fill yes)
				)
			)
		)
	)
	(footprint ""
		(layer "F.Cu")
		(at 30.061154 -146.414744)
		(property "Reference" "C176"
			(at 0 0 0)
			(layer "F.SilkS")
			(hide yes)
			(effects
				(font
					(size 1.27 1.27)
				)
			)
		)
		(property "Value" "SCD1U16V2KX-3GP"
			(at 1.1811 -2.7051 0)
			(unlocked yes)
			(layer "F.Fab")
			(hide yes)
			(effects
				(font
					(size 1.016 1.016)
					(thickness 0.1524)
				)
			)
		)
		(property "Device Type" "C402H22"
			(at 1.1811 -4.2291 0)
			(unlocked yes)
			(layer "F.Fab")
			(hide yes)
			(effects
				(font
					(size 1.016 1.016)
					(thickness 0.1524)
				)
			)
		)
		(duplicate_pad_numbers_are_jumpers no)
		(fp_rect
			(start -0.4318 0.9525)
			(end 0.4318 -0.9525)
			(stroke
				(width 0)
				(type default)
			)
			(fill no)
			(layer "F.CrtYd")
		)
		(fp_rect
			(start -0.4318 0.9525)
			(end 0.4318 -0.9525)
			(stroke
				(width 0)
				(type default)
			)
			(fill no)
			(layer "F.Fab")
		)
		(pad "1" smd custom
			(at 0 -0.4445)
			(size 0.1524 0.1524)
			(layers "F.Cu" "F.Mask" "F.Paste")
			(net "P1V53_STBY")
			(options
				(clearance outline)
				(anchor circle)
			)
			(primitives
				(gr_poly
					(pts
						(arc
							(start 0.3048 -0.2032)
							(mid 0.275042 -0.275042)
							(end 0.2032 -0.3048)
						)
						(arc
							(start -0.2032 -0.3048)
							(mid -0.275042 -0.275042)
							(end -0.3048 -0.2032)
						)
						(arc
							(start -0.3048 0.2032)
							(mid -0.275042 0.275042)
							(end -0.2032 0.3048)
						)
						(arc
							(start 0.2032 0.3048)
							(mid 0.275042 0.275042)
							(end 0.3048 0.2032)
						)
					)
					(width 0)
					(fill yes)
				)
			)
		)
		(pad "2" smd custom
			(at 0 0.4445)
			(size 0.1524 0.1524)
			(layers "F.Cu" "F.Mask" "F.Paste")
			(net "GND")
			(options
				(clearance outline)
				(anchor circle)
			)
			(primitives
				(gr_poly
					(pts
						(arc
							(start 0.3048 -0.2032)
							(mid 0.275042 -0.275042)
							(end 0.2032 -0.3048)
						)
						(arc
							(start -0.2032 -0.3048)
							(mid -0.275042 -0.275042)
							(end -0.3048 -0.2032)
						)
						(arc
							(start -0.3048 0.2032)
							(mid -0.275042 0.275042)
							(end -0.2032 0.3048)
						)
						(arc
							(start 0.2032 0.3048)
							(mid 0.275042 0.275042)
							(end 0.3048 0.2032)
						)
					)
					(width 0)
					(fill yes)
				)
			)
		)
	)
	(footprint ""
		(layer "F.Cu")
		(at 64.512952 -146.72691 -90)
		(property "Reference" "C152"
			(at 0 0 270)
			(layer "F.SilkS")
			(hide yes)
			(effects
				(font
					(size 1.27 1.27)
				)
			)
		)
		(property "Value" "SCD1U16V2JX-1-GP"
			(at 1.1811 -2.7051 270)
			(unlocked yes)
			(layer "F.Fab")
			(hide yes)
			(effects
				(font
					(size 1.016 1.016)
					(thickness 0.1524)
				)
			)
		)
		(property "Device Type" "C402H22"
			(at 1.1811 -4.2291 270)
			(unlocked yes)
			(layer "F.Fab")
			(hide yes)
			(effects
				(font
					(size 1.016 1.016)
					(thickness 0.1524)
				)
			)
		)
		(duplicate_pad_numbers_are_jumpers no)
		(fp_rect
			(start -0.4318 0.9525)
			(end 0.4318 -0.9525)
			(stroke
				(width 0)
				(type default)
			)
			(fill no)
			(layer "F.CrtYd")
		)
		(fp_rect
			(start -0.4318 0.9525)
			(end 0.4318 -0.9525)
			(stroke
				(width 0)
				(type default)
			)
			(fill no)
			(layer "F.Fab")
		)
		(pad "1" smd custom
			(at 0 -0.4445 270)
			(size 0.1524 0.1524)
			(layers "F.Cu" "F.Mask" "F.Paste")
			(net "P3V3_STBY")
			(options
				(clearance outline)
				(anchor circle)
			)
			(primitives
				(gr_poly
					(pts
						(arc
							(start 0.3048 -0.2032)
							(mid 0.275042 -0.275042)
							(end 0.2032 -0.3048)
						)
						(arc
							(start -0.2032 -0.3048)
							(mid -0.275042 -0.275042)
							(end -0.3048 -0.2032)
						)
						(arc
							(start -0.3048 0.2032)
							(mid -0.275042 0.275042)
							(end -0.2032 0.3048)
						)
						(arc
							(start 0.2032 0.3048)
							(mid 0.275042 0.275042)
							(end 0.3048 0.2032)
						)
					)
					(width 0)
					(fill yes)
				)
			)
		)
		(pad "2" smd custom
			(at 0 0.4445 270)
			(size 0.1524 0.1524)
			(layers "F.Cu" "F.Mask" "F.Paste")
			(net "GND")
			(options
				(clearance outline)
				(anchor circle)
			)
			(primitives
				(gr_poly
					(pts
						(arc
							(start 0.3048 -0.2032)
							(mid 0.275042 -0.275042)
							(end 0.2032 -0.3048)
						)
						(arc
							(start -0.2032 -0.3048)
							(mid -0.275042 -0.275042)
							(end -0.3048 -0.2032)
						)
						(arc
							(start -0.3048 0.2032)
							(mid -0.275042 0.275042)
							(end -0.2032 0.3048)
						)
						(arc
							(start 0.2032 0.3048)
							(mid 0.275042 0.275042)
							(end 0.3048 0.2032)
						)
					)
					(width 0)
					(fill yes)
				)
			)
		)
	)
	(footprint ""
		(layer "F.Cu")
		(at 61.7982 -163.4236 -90)
		(property "Reference" "PC17"
			(at 0 0 270)
			(layer "F.SilkS")
			(hide yes)
			(effects
				(font
					(size 1.27 1.27)
				)
			)
		)
		(property "Value" "SC820P50V2KX-1GP"
			(at 1.1811 -2.7051 270)
			(unlocked yes)
			(layer "F.Fab")
			(hide yes)
			(effects
				(font
					(size 1.016 1.016)
					(thickness 0.1524)
				)
			)
		)
		(property "Device Type" "C402H22"
			(at 1.1811 -4.2291 270)
			(unlocked yes)
			(layer "F.Fab")
			(hide yes)
			(effects
				(font
					(size 1.016 1.016)
					(thickness 0.1524)
				)
			)
		)
		(duplicate_pad_numbers_are_jumpers no)
		(fp_rect
			(start -0.4318 0.9525)
			(end 0.4318 -0.9525)
			(stroke
				(width 0)
				(type default)
			)
			(fill no)
			(layer "F.CrtYd")
		)
		(fp_rect
			(start -0.4318 0.9525)
			(end 0.4318 -0.9525)
			(stroke
				(width 0)
				(type default)
			)
			(fill no)
			(layer "F.Fab")
		)
		(pad "1" smd custom
			(at 0 -0.4445 270)
			(size 0.1524 0.1524)
			(layers "F.Cu" "F.Mask" "F.Paste")
			(net "VR_P1V538_STBY_SS_C")
			(options
				(clearance outline)
				(anchor circle)
			)
			(primitives
				(gr_poly
					(pts
						(arc
							(start 0.3048 -0.2032)
							(mid 0.275042 -0.275042)
							(end 0.2032 -0.3048)
						)
						(arc
							(start -0.2032 -0.3048)
							(mid -0.275042 -0.275042)
							(end -0.3048 -0.2032)
						)
						(arc
							(start -0.3048 0.2032)
							(mid -0.275042 0.275042)
							(end -0.2032 0.3048)
						)
						(arc
							(start 0.2032 0.3048)
							(mid 0.275042 0.275042)
							(end 0.3048 0.2032)
						)
					)
					(width 0)
					(fill yes)
				)
			)
		)
		(pad "2" smd custom
			(at 0 0.4445 270)
			(size 0.1524 0.1524)
			(layers "F.Cu" "F.Mask" "F.Paste")
			(net "GND")
			(options
				(clearance outline)
				(anchor circle)
			)
			(primitives
				(gr_poly
					(pts
						(arc
							(start 0.3048 -0.2032)
							(mid 0.275042 -0.275042)
							(end 0.2032 -0.3048)
						)
						(arc
							(start -0.2032 -0.3048)
							(mid -0.275042 -0.275042)
							(end -0.3048 -0.2032)
						)
						(arc
							(start -0.3048 0.2032)
							(mid -0.275042 0.275042)
							(end -0.2032 0.3048)
						)
						(arc
							(start 0.2032 0.3048)
							(mid 0.275042 0.275042)
							(end 0.3048 0.2032)
						)
					)
					(width 0)
					(fill yes)
				)
			)
		)
	)
)
